# S9S_MB_2U (Grand Teton) — schematic netlist excerpt (pin names and nets, part order shuffled) for the footprints in the layout excerpt that follows; sources: Cadence DE-HDL packaged netlist, KiCad conversion of 03242023_DA0F0TMBIJ0_F0T_Motherboard_J_brd_V01_OCP.brd

C296  Q_CAP  22UF 4V 20% X6S  pkg C0402  page 77 : A = PVCCIN_CPU1 ; B = GND
R3174  Q_RES  10K 1% CHIP  pkg 0402LF  page 159 : A = SGPIO_OCP_V3_2_DATAIN ; B = P3V3_OCP_V3_2

(kicad_pcb
	(version 20260206)
	(generator "pcbnew")
	(generator_version "10.0")
	(general
		(thickness 1.6)
		(legacy_teardrops no)
	)
	(paper "A4")
	(title_block
		(title "03242023_DA0F0TMBIJ0_F0T_Motherboard_J_brd_V01_OCP.brd")
		(comment 1 "Grand Teton / footprints 3562-3563 of 6105")
	)
	(layers
		(0 "F.Cu" signal "TOP")
		(4 "In1.Cu" signal "GND")
		(6 "In2.Cu" signal "IN1")
		(8 "In3.Cu" signal "GND1")
		(10 "In4.Cu" signal "IN2")
		(12 "In5.Cu" signal "GND2")
		(14 "In6.Cu" signal "IN3")
		(16 "In7.Cu" signal "GND3")
		(18 "In8.Cu" signal "VCC")
		(20 "In9.Cu" signal "VCC1")
		(22 "In10.Cu" signal "GND4")
		(24 "In11.Cu" signal "IN4")
		(26 "In12.Cu" signal "GND5")
		(28 "In13.Cu" signal "IN5")
		(30 "In14.Cu" signal "GND6")
		(32 "In15.Cu" signal "IN6")
		(34 "In16.Cu" signal "GND7")
		(2 "B.Cu" signal "BOTTOM")
		(9 "F.Adhes" user "F.Adhesive")
		(11 "B.Adhes" user "B.Adhesive")
		(13 "F.Paste" user "Package Geometry/Pastemask Top")
		(15 "B.Paste" user "Package Geometry/Pastemask Bottom")
		(5 "F.SilkS" user "Ref Des/Silkscreen Top")
		(7 "B.SilkS" user "Ref Des/Silkscreen Bottom")
		(1 "F.Mask" user "Board Geometry/Soldermask Top")
		(3 "B.Mask" user "Board Geometry/Soldermask Bottom")
		(17 "Dwgs.User" user "User.Drawings")
		(19 "Cmts.User" user "User.Comments")
		(21 "Eco1.User" user "User.Eco1")
		(23 "Eco2.User" user "User.Eco2")
		(25 "Edge.Cuts" user "Board Geometry/Outline")
		(27 "Margin" user)
		(31 "F.CrtYd" user "Package Geometry/Place Bound Top")
		(29 "B.CrtYd" user "Package Geometry/Place Bound Bottom")
		(35 "F.Fab" user "Ref Des/Assembly Top")
		(33 "B.Fab" user "Ref Des/Assembly Bottom")
	)
	(footprint ""
		(layer "F.Cu")
		(at 157.02788 -117.566948 180)
		(property "Reference" "R3174"
			(at 0 0 180)
			(layer "F.SilkS")
			(hide yes)
			(effects
				(font
					(size 1.27 1.27)
				)
			)
		)
		(property "Value" ""
			(at 0 0 180)
			(layer "F.Fab")
			(effects
				(font
					(size 1.27 1.27)
				)
			)
		)
		(duplicate_pad_numbers_are_jumpers no)
		(fp_line
			(start 0.7874 0.4064)
			(end -0.7874 0.4064)
			(stroke
				(width 0.1524)
				(type default)
			)
			(layer "F.SilkS")
		)
		(fp_line
			(start 0.7874 -0.4064)
			(end 0.7874 0.4064)
			(stroke
				(width 0.1524)
				(type default)
			)
			(layer "F.SilkS")
		)
		(fp_line
			(start -0.7874 0.4064)
			(end -0.7874 -0.4064)
			(stroke
				(width 0.1524)
				(type default)
			)
			(layer "F.SilkS")
		)
		(fp_line
			(start -0.7874 -0.4064)
			(end 0.7874 -0.4064)
			(stroke
				(width 0.1524)
				(type default)
			)
			(layer "F.SilkS")
		)
		(fp_line
			(start 0.67945 0.3048)
			(end 0.120396 0.3048)
			(stroke
				(width 0.1)
				(type default)
			)
			(layer "F.Fab")
		)
		(fp_line
			(start 0.67945 -0.3048)
			(end 0.67945 0.3048)
			(stroke
				(width 0.1)
				(type default)
			)
			(layer "F.Fab")
		)
		(fp_line
			(start 0.12065 -0.2794)
			(end 0.12065 -0.3048)
			(stroke
				(width 0.1)
				(type default)
			)
			(layer "F.Fab")
		)
		(fp_line
			(start 0.12065 -0.3048)
			(end 0.67945 -0.3048)
			(stroke
				(width 0.1)
				(type default)
			)
			(layer "F.Fab")
		)
		(fp_line
			(start 0.120396 0.3048)
			(end 0.120396 0.2794)
			(stroke
				(width 0.1)
				(type default)
			)
			(layer "F.Fab")
		)
		(fp_line
			(start 0.120396 0.2794)
			(end -0.12065 0.2794)
			(stroke
				(width 0.1)
				(type default)
			)
			(layer "F.Fab")
		)
		(fp_line
			(start -0.12065 0.3048)
			(end -0.67945 0.3048)
			(stroke
				(width 0.1)
				(type default)
			)
			(layer "F.Fab")
		)
		(fp_line
			(start -0.12065 0.2794)
			(end -0.12065 0.3048)
			(stroke
				(width 0.1)
				(type default)
			)
			(layer "F.Fab")
		)
		(fp_line
			(start -0.12065 -0.2794)
			(end 0.12065 -0.2794)
			(stroke
				(width 0.1)
				(type default)
			)
			(layer "F.Fab")
		)
		(fp_line
			(start -0.12065 -0.305054)
			(end -0.12065 -0.2794)
			(stroke
				(width 0.1)
				(type default)
			)
			(layer "F.Fab")
		)
		(fp_line
			(start -0.67945 0.3048)
			(end -0.67945 -0.305054)
			(stroke
				(width 0.1)
				(type default)
			)
			(layer "F.Fab")
		)
		(fp_line
			(start -0.67945 -0.305054)
			(end -0.12065 -0.305054)
			(stroke
				(width 0.1)
				(type default)
			)
			(layer "F.Fab")
		)
		(pad "1" smd circle
			(at -0.40005 0 180)
			(size 0 0)
			(layers "F.Cu" "F.Mask" "F.Paste")
			(net "SGPIO_OCP_V3_2_DATAIN")
		)
		(pad "2" smd circle
			(at 0.40005 0 180)
			(size 0 0)
			(layers "F.Cu" "F.Mask" "F.Paste")
			(net "P3V3_OCP_V3_2")
		)
	)
	(footprint ""
		(layer "F.Cu")
		(at 107.28833 -240.277142 90)
		(property "Reference" "C296"
			(at 0 0 90)
			(layer "F.SilkS")
			(hide yes)
			(effects
				(font
					(size 1.27 1.27)
				)
			)
		)
		(property "Value" ""
			(at 0 0 90)
			(layer "F.Fab")
			(effects
				(font
					(size 1.27 1.27)
				)
			)
		)
		(duplicate_pad_numbers_are_jumpers no)
		(fp_line
			(start 0.7874 -0.4064)
			(end 0.7874 0.4064)
			(stroke
				(width 0.1524)
				(type default)
			)
			(layer "F.SilkS")
		)
		(fp_line
			(start -0.7874 -0.4064)
			(end 0.7874 -0.4064)
			(stroke
				(width 0.1524)
				(type default)
			)
			(layer "F.SilkS")
		)
		(fp_line
			(start 0.7874 0.4064)
			(end -0.7874 0.4064)
			(stroke
				(width 0.1524)
				(type default)
			)
			(layer "F.SilkS")
		)
		(fp_line
			(start -0.7874 0.4064)
			(end -0.7874 -0.4064)
			(stroke
				(width 0.1524)
				(type default)
			)
			(layer "F.SilkS")
		)
		(fp_line
			(start -0.12065 -0.305054)
			(end -0.12065 -0.2794)
			(stroke
				(width 0.1)
				(type default)
			)
			(layer "F.Fab")
		)
		(fp_line
			(start -0.67945 -0.305054)
			(end -0.12065 -0.305054)
			(stroke
				(width 0.1)
				(type default)
			)
			(layer "F.Fab")
		)
		(fp_line
			(start 0.67945 -0.3048)
			(end 0.67945 0.3048)
			(stroke
				(width 0.1)
				(type default)
			)
			(layer "F.Fab")
		)
		(fp_line
			(start 0.12065 -0.3048)
			(end 0.67945 -0.3048)
			(stroke
				(width 0.1)
				(type default)
			)
			(layer "F.Fab")
		)
		(fp_line
			(start 0.12065 -0.2794)
			(end 0.12065 -0.3048)
			(stroke
				(width 0.1)
				(type default)
			)
			(layer "F.Fab")
		)
		(fp_line
			(start -0.12065 -0.2794)
			(end 0.12065 -0.2794)
			(stroke
				(width 0.1)
				(type default)
			)
			(layer "F.Fab")
		)
		(fp_line
			(start 0.120396 0.2794)
			(end -0.12065 0.2794)
			(stroke
				(width 0.1)
				(type default)
			)
			(layer "F.Fab")
		)
		(fp_line
			(start -0.12065 0.2794)
			(end -0.12065 0.3048)
			(stroke
				(width 0.1)
				(type default)
			)
			(layer "F.Fab")
		)
		(fp_line
			(start 0.67945 0.3048)
			(end 0.120396 0.3048)
			(stroke
				(width 0.1)
				(type default)
			)
			(layer "F.Fab")
		)
		(fp_line
			(start 0.120396 0.3048)
			(end 0.120396 0.2794)
			(stroke
				(width 0.1)
				(type default)
			)
			(layer "F.Fab")
		)
		(fp_line
			(start -0.12065 0.3048)
			(end -0.67945 0.3048)
			(stroke
				(width 0.1)
				(type default)
			)
			(layer "F.Fab")
		)
		(fp_line
			(start -0.67945 0.3048)
			(end -0.67945 -0.305054)
			(stroke
				(width 0.1)
				(type default)
			)
			(layer "F.Fab")
		)
		(pad "1" smd circle
			(at -0.40005 0 90)
			(size 0 0)
			(layers "F.Cu" "F.Mask" "F.Paste")
			(net "PVCCIN_CPU1")
		)
		(pad "2" smd circle
			(at 0.40005 0 90)
			(size 0 0)
			(layers "F.Cu" "F.Mask" "F.Paste")
			(net "GND")
		)
	)
)
